# S9S_MB_2U (Grand Teton) — schematic netlist excerpt (pin names and nets, part order shuffled) for the footprints in the layout excerpt that follows; sources: Cadence DE-HDL packaged netlist, KiCad conversion of 03242023_DA0F0TMBIJ0_F0T_Motherboard_J_brd_V01_OCP.brd

R2235  Q_RES  1K 1% CHIP  pkg 0402LF  page 195 : A = FM_BOARD_SKU_ID4 ; B = GND
PC1251  Q_CAP  0.1UF 25V 10% X7R  pkg 0402  page 281 : A = PVPP_HBM_CPU0_REF ; B = SH_PVPP_HBM_CPU0_N

(kicad_pcb
	(version 20260206)
	(generator "pcbnew")
	(generator_version "10.0")
	(general
		(thickness 1.6)
		(legacy_teardrops no)
	)
	(paper "A4")
	(title_block
		(title "03242023_DA0F0TMBIJ0_F0T_Motherboard_J_brd_V01_OCP.brd")
		(comment 1 "Grand Teton / footprints 3165-3166 of 6105")
	)
	(layers
		(0 "F.Cu" signal "TOP")
		(4 "In1.Cu" signal "GND")
		(6 "In2.Cu" signal "IN1")
		(8 "In3.Cu" signal "GND1")
		(10 "In4.Cu" signal "IN2")
		(12 "In5.Cu" signal "GND2")
		(14 "In6.Cu" signal "IN3")
		(16 "In7.Cu" signal "GND3")
		(18 "In8.Cu" signal "VCC")
		(20 "In9.Cu" signal "VCC1")
		(22 "In10.Cu" signal "GND4")
		(24 "In11.Cu" signal "IN4")
		(26 "In12.Cu" signal "GND5")
		(28 "In13.Cu" signal "IN5")
		(30 "In14.Cu" signal "GND6")
		(32 "In15.Cu" signal "IN6")
		(34 "In16.Cu" signal "GND7")
		(2 "B.Cu" signal "BOTTOM")
		(9 "F.Adhes" user "F.Adhesive")
		(11 "B.Adhes" user "B.Adhesive")
		(13 "F.Paste" user "Package Geometry/Pastemask Top")
		(15 "B.Paste" user "Package Geometry/Pastemask Bottom")
		(5 "F.SilkS" user "Ref Des/Silkscreen Top")
		(7 "B.SilkS" user "Ref Des/Silkscreen Bottom")
		(1 "F.Mask" user "Board Geometry/Soldermask Top")
		(3 "B.Mask" user "Board Geometry/Soldermask Bottom")
		(17 "Dwgs.User" user "User.Drawings")
		(19 "Cmts.User" user "User.Comments")
		(21 "Eco1.User" user "User.Eco1")
		(23 "Eco2.User" user "User.Eco2")
		(25 "Edge.Cuts" user "Board Geometry/Outline")
		(27 "Margin" user)
		(31 "F.CrtYd" user "Package Geometry/Place Bound Top")
		(29 "B.CrtYd" user "Package Geometry/Place Bound Bottom")
		(35 "F.Fab" user "Ref Des/Assembly Top")
		(33 "B.Fab" user "Ref Des/Assembly Bottom")
	)
	(footprint ""
		(layer "F.Cu")
		(at 320.8401 -76.585064 90)
		(property "Reference" "R2235"
			(at 0 0 90)
			(layer "F.SilkS")
			(hide yes)
			(effects
				(font
					(size 1.27 1.27)
				)
			)
		)
		(property "Value" ""
			(at 0 0 90)
			(layer "F.Fab")
			(effects
				(font
					(size 1.27 1.27)
				)
			)
		)
		(duplicate_pad_numbers_are_jumpers no)
		(fp_line
			(start 0.7874 -0.4064)
			(end 0.7874 0.4064)
			(stroke
				(width 0.1524)
				(type default)
			)
			(layer "F.SilkS")
		)
		(fp_line
			(start -0.7874 -0.4064)
			(end 0.7874 -0.4064)
			(stroke
				(width 0.1524)
				(type default)
			)
			(layer "F.SilkS")
		)
		(fp_line
			(start 0.7874 0.4064)
			(end -0.7874 0.4064)
			(stroke
				(width 0.1524)
				(type default)
			)
			(layer "F.SilkS")
		)
		(fp_line
			(start -0.7874 0.4064)
			(end -0.7874 -0.4064)
			(stroke
				(width 0.1524)
				(type default)
			)
			(layer "F.SilkS")
		)
		(fp_line
			(start -0.12065 -0.305054)
			(end -0.12065 -0.2794)
			(stroke
				(width 0.1)
				(type default)
			)
			(layer "F.Fab")
		)
		(fp_line
			(start -0.67945 -0.305054)
			(end -0.12065 -0.305054)
			(stroke
				(width 0.1)
				(type default)
			)
			(layer "F.Fab")
		)
		(fp_line
			(start 0.67945 -0.3048)
			(end 0.67945 0.3048)
			(stroke
				(width 0.1)
				(type default)
			)
			(layer "F.Fab")
		)
		(fp_line
			(start 0.12065 -0.3048)
			(end 0.67945 -0.3048)
			(stroke
				(width 0.1)
				(type default)
			)
			(layer "F.Fab")
		)
		(fp_line
			(start 0.12065 -0.2794)
			(end 0.12065 -0.3048)
			(stroke
				(width 0.1)
				(type default)
			)
			(layer "F.Fab")
		)
		(fp_line
			(start -0.12065 -0.2794)
			(end 0.12065 -0.2794)
			(stroke
				(width 0.1)
				(type default)
			)
			(layer "F.Fab")
		)
		(fp_line
			(start 0.120396 0.2794)
			(end -0.12065 0.2794)
			(stroke
				(width 0.1)
				(type default)
			)
			(layer "F.Fab")
		)
		(fp_line
			(start -0.12065 0.2794)
			(end -0.12065 0.3048)
			(stroke
				(width 0.1)
				(type default)
			)
			(layer "F.Fab")
		)
		(fp_line
			(start 0.67945 0.3048)
			(end 0.120396 0.3048)
			(stroke
				(width 0.1)
				(type default)
			)
			(layer "F.Fab")
		)
		(fp_line
			(start 0.120396 0.3048)
			(end 0.120396 0.2794)
			(stroke
				(width 0.1)
				(type default)
			)
			(layer "F.Fab")
		)
		(fp_line
			(start -0.12065 0.3048)
			(end -0.67945 0.3048)
			(stroke
				(width 0.1)
				(type default)
			)
			(layer "F.Fab")
		)
		(fp_line
			(start -0.67945 0.3048)
			(end -0.67945 -0.305054)
			(stroke
				(width 0.1)
				(type default)
			)
			(layer "F.Fab")
		)
		(pad "1" smd circle
			(at -0.40005 0 90)
			(size 0 0)
			(layers "F.Cu" "F.Mask" "F.Paste")
			(net "FM_BOARD_SKU_ID4")
		)
		(pad "2" smd circle
			(at 0.40005 0 90)
			(size 0 0)
			(layers "F.Cu" "F.Mask" "F.Paste")
			(net "GND")
		)
	)
	(footprint ""
		(layer "F.Cu")
		(at 369.369848 -358.430576)
		(property "Reference" "PC1251"
			(at 0 0 0)
			(layer "F.SilkS")
			(hide yes)
			(effects
				(font
					(size 1.27 1.27)
				)
			)
		)
		(property "Value" ""
			(at 0 0 0)
			(layer "F.Fab")
			(effects
				(font
					(size 1.27 1.27)
				)
			)
		)
		(duplicate_pad_numbers_are_jumpers no)
		(fp_line
			(start -0.7874 -0.4064)
			(end 0.7874 -0.4064)
			(stroke
				(width 0.1524)
				(type default)
			)
			(layer "F.SilkS")
		)
		(fp_line
			(start -0.7874 0.4064)
			(end -0.7874 -0.4064)
			(stroke
				(width 0.1524)
				(type default)
			)
			(layer "F.SilkS")
		)
		(fp_line
			(start 0.7874 -0.4064)
			(end 0.7874 0.4064)
			(stroke
				(width 0.1524)
				(type default)
			)
			(layer "F.SilkS")
		)
		(fp_line
			(start 0.7874 0.4064)
			(end -0.7874 0.4064)
			(stroke
				(width 0.1524)
				(type default)
			)
			(layer "F.SilkS")
		)
		(fp_line
			(start -0.67945 -0.305054)
			(end -0.12065 -0.305054)
			(stroke
				(width 0.1)
				(type default)
			)
			(layer "F.Fab")
		)
		(fp_line
			(start -0.67945 0.3048)
			(end -0.67945 -0.305054)
			(stroke
				(width 0.1)
				(type default)
			)
			(layer "F.Fab")
		)
		(fp_line
			(start -0.12065 -0.305054)
			(end -0.12065 -0.2794)
			(stroke
				(width 0.1)
				(type default)
			)
			(layer "F.Fab")
		)
		(fp_line
			(start -0.12065 -0.2794)
			(end 0.12065 -0.2794)
			(stroke
				(width 0.1)
				(type default)
			)
			(layer "F.Fab")
		)
		(fp_line
			(start -0.12065 0.2794)
			(end -0.12065 0.3048)
			(stroke
				(width 0.1)
				(type default)
			)
			(layer "F.Fab")
		)
		(fp_line
			(start -0.12065 0.3048)
			(end -0.67945 0.3048)
			(stroke
				(width 0.1)
				(type default)
			)
			(layer "F.Fab")
		)
		(fp_line
			(start 0.120396 0.2794)
			(end -0.12065 0.2794)
			(stroke
				(width 0.1)
				(type default)
			)
			(layer "F.Fab")
		)
		(fp_line
			(start 0.120396 0.3048)
			(end 0.120396 0.2794)
			(stroke
				(width 0.1)
				(type default)
			)
			(layer "F.Fab")
		)
		(fp_line
			(start 0.12065 -0.3048)
			(end 0.67945 -0.3048)
			(stroke
				(width 0.1)
				(type default)
			)
			(layer "F.Fab")
		)
		(fp_line
			(start 0.12065 -0.2794)
			(end 0.12065 -0.3048)
			(stroke
				(width 0.1)
				(type default)
			)
			(layer "F.Fab")
		)
		(fp_line
			(start 0.67945 -0.3048)
			(end 0.67945 0.3048)
			(stroke
				(width 0.1)
				(type default)
			)
			(layer "F.Fab")
		)
		(fp_line
			(start 0.67945 0.3048)
			(end 0.120396 0.3048)
			(stroke
				(width 0.1)
				(type default)
			)
			(layer "F.Fab")
		)
		(pad "1" smd circle
			(at -0.40005 0)
			(size 0 0)
			(layers "F.Cu" "F.Mask" "F.Paste")
			(net "PVPP_HBM_CPU0_REF")
		)
		(pad "2" smd circle
			(at 0.40005 0)
			(size 0 0)
			(layers "F.Cu" "F.Mask" "F.Paste")
			(net "SH_PVPP_HBM_CPU0_N")
		)
	)
)
